# T6G (Grand Teton) — schematic netlist excerpt (pin names and nets, part order shuffled) for the footprints in the layout excerpt that follows; sources: Cadence DE-HDL packaged netlist, KiCad conversion of 04192023_DAF0TMB3IC0_F0TG_MB_C_brd_V02_OCP.brd

C1862  Q_CAP  0.1UF 25V 10% X7R  pkg 0402  page 247 : A = P3V3_OCP_SFF ; B = GND
C731  Q_CAP_DIFFBUS  DIFF BUS_0.22UF 6.3V 20% X6S  pkg C0201  page 66 : \1\ = P5E_CPU1_P1_TX_C_DP<5> ; \2\ = P5E_CPU1_P1_TX_DP<5>
PC428  Q_CAP  0.22UF 16V 10% X7R  pkg 0402  page 220 : A = SW_PVDDCR_CPU1_P1_BOOT5_R ; B = SW_PVDDCR_CPU1_P1_BOOTR5

(kicad_pcb
	(version 20260206)
	(generator "pcbnew")
	(generator_version "10.0")
	(general
		(thickness 1.6)
		(legacy_teardrops no)
	)
	(paper "A4")
	(title_block
		(title "04192023_DAF0TMB3IC0_F0TG_MB_C_brd_V02_OCP.brd")
		(comment 1 "Grand Teton / footprints 3457-3459 of 8354")
	)
	(layers
		(0 "F.Cu" signal "TOP")
		(4 "In1.Cu" signal "GND")
		(6 "In2.Cu" signal "IN1")
		(8 "In3.Cu" signal "GND1")
		(10 "In4.Cu" signal "IN2")
		(12 "In5.Cu" signal "GND2")
		(14 "In6.Cu" signal "IN3")
		(16 "In7.Cu" signal "GND3")
		(18 "In8.Cu" signal "VCC")
		(20 "In9.Cu" signal "VCC1")
		(22 "In10.Cu" signal "GND4")
		(24 "In11.Cu" signal "IN4")
		(26 "In12.Cu" signal "GND5")
		(28 "In13.Cu" signal "IN5")
		(30 "In14.Cu" signal "GND6")
		(32 "In15.Cu" signal "IN6")
		(34 "In16.Cu" signal "GND7")
		(2 "B.Cu" signal "BOTTOM")
		(9 "F.Adhes" user "F.Adhesive")
		(11 "B.Adhes" user "B.Adhesive")
		(13 "F.Paste" user "Package Geometry/Pastemask Top")
		(15 "B.Paste" user "Package Geometry/Pastemask Bottom")
		(5 "F.SilkS" user "Ref Des/Silkscreen Top")
		(7 "B.SilkS" user "Ref Des/Silkscreen Bottom")
		(1 "F.Mask" user "Board Geometry/Soldermask Top")
		(3 "B.Mask" user "Board Geometry/Soldermask Bottom")
		(17 "Dwgs.User" user "User.Drawings")
		(19 "Cmts.User" user "User.Comments")
		(21 "Eco1.User" user "User.Eco1")
		(23 "Eco2.User" user "User.Eco2")
		(25 "Edge.Cuts" user "Board Geometry/Outline")
		(27 "Margin" user)
		(31 "F.CrtYd" user "Package Geometry/Place Bound Top")
		(29 "B.CrtYd" user "Package Geometry/Place Bound Bottom")
		(35 "F.Fab" user "Ref Des/Assembly Top")
		(33 "B.Fab" user "Ref Des/Assembly Bottom")
	)
	(footprint ""
		(layer "F.Cu")
		(at 97.239328 -339.681058 -90)
		(property "Reference" "PC428"
			(at 0 0 270)
			(layer "F.SilkS")
			(hide yes)
			(effects
				(font
					(size 1.27 1.27)
				)
			)
		)
		(property "Value" ""
			(at 0 0 270)
			(layer "F.Fab")
			(effects
				(font
					(size 1.27 1.27)
				)
			)
		)
		(duplicate_pad_numbers_are_jumpers no)
		(fp_line
			(start -0.7874 0.4064)
			(end -0.7874 -0.4064)
			(stroke
				(width 0.1524)
				(type default)
			)
			(layer "F.SilkS")
		)
		(fp_line
			(start 0.7874 0.4064)
			(end -0.7874 0.4064)
			(stroke
				(width 0.1524)
				(type default)
			)
			(layer "F.SilkS")
		)
		(fp_line
			(start -0.7874 -0.4064)
			(end 0.7874 -0.4064)
			(stroke
				(width 0.1524)
				(type default)
			)
			(layer "F.SilkS")
		)
		(fp_line
			(start 0.7874 -0.4064)
			(end 0.7874 0.4064)
			(stroke
				(width 0.1524)
				(type default)
			)
			(layer "F.SilkS")
		)
		(fp_line
			(start -0.67945 0.3048)
			(end -0.67945 -0.305054)
			(stroke
				(width 0.1)
				(type default)
			)
			(layer "F.Fab")
		)
		(fp_line
			(start -0.12065 0.3048)
			(end -0.67945 0.3048)
			(stroke
				(width 0.1)
				(type default)
			)
			(layer "F.Fab")
		)
		(fp_line
			(start 0.120396 0.3048)
			(end 0.120396 0.2794)
			(stroke
				(width 0.1)
				(type default)
			)
			(layer "F.Fab")
		)
		(fp_line
			(start 0.67945 0.3048)
			(end 0.120396 0.3048)
			(stroke
				(width 0.1)
				(type default)
			)
			(layer "F.Fab")
		)
		(fp_line
			(start -0.12065 0.2794)
			(end -0.12065 0.3048)
			(stroke
				(width 0.1)
				(type default)
			)
			(layer "F.Fab")
		)
		(fp_line
			(start 0.120396 0.2794)
			(end -0.12065 0.2794)
			(stroke
				(width 0.1)
				(type default)
			)
			(layer "F.Fab")
		)
		(fp_line
			(start -0.12065 -0.2794)
			(end 0.12065 -0.2794)
			(stroke
				(width 0.1)
				(type default)
			)
			(layer "F.Fab")
		)
		(fp_line
			(start 0.12065 -0.2794)
			(end 0.12065 -0.3048)
			(stroke
				(width 0.1)
				(type default)
			)
			(layer "F.Fab")
		)
		(fp_line
			(start 0.12065 -0.3048)
			(end 0.67945 -0.3048)
			(stroke
				(width 0.1)
				(type default)
			)
			(layer "F.Fab")
		)
		(fp_line
			(start 0.67945 -0.3048)
			(end 0.67945 0.3048)
			(stroke
				(width 0.1)
				(type default)
			)
			(layer "F.Fab")
		)
		(fp_line
			(start -0.67945 -0.305054)
			(end -0.12065 -0.305054)
			(stroke
				(width 0.1)
				(type default)
			)
			(layer "F.Fab")
		)
		(fp_line
			(start -0.12065 -0.305054)
			(end -0.12065 -0.2794)
			(stroke
				(width 0.1)
				(type default)
			)
			(layer "F.Fab")
		)
		(pad "1" smd circle
			(at -0.40005 0 270)
			(size 0 0)
			(layers "F.Cu" "F.Mask" "F.Paste")
			(net "SW_PVDDCR_CPU1_P1_BOOT5_R")
		)
		(pad "2" smd circle
			(at 0.40005 0 270)
			(size 0 0)
			(layers "F.Cu" "F.Mask" "F.Paste")
			(net "SW_PVDDCR_CPU1_P1_BOOTR5")
		)
	)
	(footprint ""
		(layer "F.Cu")
		(at 410.8196 -77.513434 90)
		(property "Reference" "C1862"
			(at 0 0 90)
			(layer "F.SilkS")
			(hide yes)
			(effects
				(font
					(size 1.27 1.27)
				)
			)
		)
		(property "Value" ""
			(at 0 0 90)
			(layer "F.Fab")
			(effects
				(font
					(size 1.27 1.27)
				)
			)
		)
		(duplicate_pad_numbers_are_jumpers no)
		(fp_line
			(start 0.7874 -0.4064)
			(end 0.7874 0.4064)
			(stroke
				(width 0.1524)
				(type default)
			)
			(layer "F.SilkS")
		)
		(fp_line
			(start -0.7874 -0.4064)
			(end 0.7874 -0.4064)
			(stroke
				(width 0.1524)
				(type default)
			)
			(layer "F.SilkS")
		)
		(fp_line
			(start 0.7874 0.4064)
			(end -0.7874 0.4064)
			(stroke
				(width 0.1524)
				(type default)
			)
			(layer "F.SilkS")
		)
		(fp_line
			(start -0.7874 0.4064)
			(end -0.7874 -0.4064)
			(stroke
				(width 0.1524)
				(type default)
			)
			(layer "F.SilkS")
		)
		(fp_line
			(start -0.12065 -0.305054)
			(end -0.12065 -0.2794)
			(stroke
				(width 0.1)
				(type default)
			)
			(layer "F.Fab")
		)
		(fp_line
			(start -0.67945 -0.305054)
			(end -0.12065 -0.305054)
			(stroke
				(width 0.1)
				(type default)
			)
			(layer "F.Fab")
		)
		(fp_line
			(start 0.67945 -0.3048)
			(end 0.67945 0.3048)
			(stroke
				(width 0.1)
				(type default)
			)
			(layer "F.Fab")
		)
		(fp_line
			(start 0.12065 -0.3048)
			(end 0.67945 -0.3048)
			(stroke
				(width 0.1)
				(type default)
			)
			(layer "F.Fab")
		)
		(fp_line
			(start 0.12065 -0.2794)
			(end 0.12065 -0.3048)
			(stroke
				(width 0.1)
				(type default)
			)
			(layer "F.Fab")
		)
		(fp_line
			(start -0.12065 -0.2794)
			(end 0.12065 -0.2794)
			(stroke
				(width 0.1)
				(type default)
			)
			(layer "F.Fab")
		)
		(fp_line
			(start 0.120396 0.2794)
			(end -0.12065 0.2794)
			(stroke
				(width 0.1)
				(type default)
			)
			(layer "F.Fab")
		)
		(fp_line
			(start -0.12065 0.2794)
			(end -0.12065 0.3048)
			(stroke
				(width 0.1)
				(type default)
			)
			(layer "F.Fab")
		)
		(fp_line
			(start 0.67945 0.3048)
			(end 0.120396 0.3048)
			(stroke
				(width 0.1)
				(type default)
			)
			(layer "F.Fab")
		)
		(fp_line
			(start 0.120396 0.3048)
			(end 0.120396 0.2794)
			(stroke
				(width 0.1)
				(type default)
			)
			(layer "F.Fab")
		)
		(fp_line
			(start -0.12065 0.3048)
			(end -0.67945 0.3048)
			(stroke
				(width 0.1)
				(type default)
			)
			(layer "F.Fab")
		)
		(fp_line
			(start -0.67945 0.3048)
			(end -0.67945 -0.305054)
			(stroke
				(width 0.1)
				(type default)
			)
			(layer "F.Fab")
		)
		(pad "1" smd circle
			(at -0.40005 0 90)
			(size 0 0)
			(layers "F.Cu" "F.Mask" "F.Paste")
			(net "P3V3_OCP_SFF")
		)
		(pad "2" smd circle
			(at 0.40005 0 90)
			(size 0 0)
			(layers "F.Cu" "F.Mask" "F.Paste")
			(net "GND")
		)
	)
	(footprint ""
		(layer "F.Cu")
		(at 82.324702 -373.03583 -90)
		(property "Reference" "C731"
			(at 0 0 270)
			(layer "F.SilkS")
			(hide yes)
			(effects
				(font
					(size 1.27 1.27)
				)
			)
		)
		(property "Value" ""
			(at 0 0 270)
			(layer "F.Fab")
			(effects
				(font
					(size 1.27 1.27)
				)
			)
		)
		(duplicate_pad_numbers_are_jumpers no)
		(fp_line
			(start -0.299974 0.150114)
			(end -0.299974 -0.150114)
			(stroke
				(width 0.1)
				(type default)
			)
			(layer "F.Fab")
		)
		(fp_line
			(start 0.299974 0.150114)
			(end -0.299974 0.150114)
			(stroke
				(width 0.1)
				(type default)
			)
			(layer "F.Fab")
		)
		(fp_line
			(start -0.299974 -0.150114)
			(end 0.299974 -0.150114)
			(stroke
				(width 0.1)
				(type default)
			)
			(layer "F.Fab")
		)
		(fp_line
			(start 0.299974 -0.150114)
			(end 0.299974 0.150114)
			(stroke
				(width 0.1)
				(type default)
			)
			(layer "F.Fab")
		)
		(pad "1" smd rect
			(at -0.2667 0 270)
			(size 0.3048 0.381)
			(layers "F.Cu" "F.Mask" "F.Paste")
			(net "P5E_CPU1_P1_TX_C_DP<5>")
		)
		(pad "2" smd rect
			(at 0.2667 0 270)
			(size 0.3048 0.381)
			(layers "F.Cu" "F.Mask" "F.Paste")
			(net "P5E_CPU1_P1_TX_DP<5>")
		)
	)
)
